# S9S_MB_2U (Grand Teton) — schematic netlist excerpt (pin names and nets, part order shuffled) for the footprints in the layout excerpt that follows; sources: Cadence DE-HDL packaged netlist, KiCad conversion of 03242023_DA0F0TMBIJ0_F0T_Motherboard_J_brd_V01_OCP.brd

R3622  Q_RES  4.7K 1% CHIP  pkg 0402LF  page 172 : A = P3V3_AUX ; B = INA230_5_A0
C2037  Q_CAP  8.2PF 50V 0.1P NP0  pkg C0402  page 208 : A = XTAL_CLK_GEN1_25M_X2 ; B = GND

(kicad_pcb
	(version 20260206)
	(generator "pcbnew")
	(generator_version "10.0")
	(general
		(thickness 1.6)
		(legacy_teardrops no)
	)
	(paper "A4")
	(title_block
		(title "03242023_DA0F0TMBIJ0_F0T_Motherboard_J_brd_V01_OCP.brd")
		(comment 1 "Grand Teton / footprints 343-344 of 6105")
	)
	(layers
		(0 "F.Cu" signal "TOP")
		(4 "In1.Cu" signal "GND")
		(6 "In2.Cu" signal "IN1")
		(8 "In3.Cu" signal "GND1")
		(10 "In4.Cu" signal "IN2")
		(12 "In5.Cu" signal "GND2")
		(14 "In6.Cu" signal "IN3")
		(16 "In7.Cu" signal "GND3")
		(18 "In8.Cu" signal "VCC")
		(20 "In9.Cu" signal "VCC1")
		(22 "In10.Cu" signal "GND4")
		(24 "In11.Cu" signal "IN4")
		(26 "In12.Cu" signal "GND5")
		(28 "In13.Cu" signal "IN5")
		(30 "In14.Cu" signal "GND6")
		(32 "In15.Cu" signal "IN6")
		(34 "In16.Cu" signal "GND7")
		(2 "B.Cu" signal "BOTTOM")
		(9 "F.Adhes" user "F.Adhesive")
		(11 "B.Adhes" user "B.Adhesive")
		(13 "F.Paste" user "Package Geometry/Pastemask Top")
		(15 "B.Paste" user "Package Geometry/Pastemask Bottom")
		(5 "F.SilkS" user "Ref Des/Silkscreen Top")
		(7 "B.SilkS" user "Ref Des/Silkscreen Bottom")
		(1 "F.Mask" user "Board Geometry/Soldermask Top")
		(3 "B.Mask" user "Board Geometry/Soldermask Bottom")
		(17 "Dwgs.User" user "User.Drawings")
		(19 "Cmts.User" user "User.Comments")
		(21 "Eco1.User" user "User.Eco1")
		(23 "Eco2.User" user "User.Eco2")
		(25 "Edge.Cuts" user "Board Geometry/Outline")
		(27 "Margin" user)
		(31 "F.CrtYd" user "Package Geometry/Place Bound Top")
		(29 "B.CrtYd" user "Package Geometry/Place Bound Bottom")
		(35 "F.Fab" user "Ref Des/Assembly Top")
		(33 "B.Fab" user "Ref Des/Assembly Bottom")
	)
	(footprint ""
		(layer "F.Cu")
		(at 210.086956 -30.276292 90)
		(property "Reference" "R3622"
			(at 0 0 90)
			(layer "F.SilkS")
			(hide yes)
			(effects
				(font
					(size 1.27 1.27)
				)
			)
		)
		(property "Value" ""
			(at 0 0 90)
			(layer "F.Fab")
			(effects
				(font
					(size 1.27 1.27)
				)
			)
		)
		(duplicate_pad_numbers_are_jumpers no)
		(fp_line
			(start 0.7874 -0.4064)
			(end 0.7874 0.4064)
			(stroke
				(width 0.1524)
				(type default)
			)
			(layer "F.SilkS")
		)
		(fp_line
			(start -0.7874 -0.4064)
			(end 0.7874 -0.4064)
			(stroke
				(width 0.1524)
				(type default)
			)
			(layer "F.SilkS")
		)
		(fp_line
			(start 0.7874 0.4064)
			(end -0.7874 0.4064)
			(stroke
				(width 0.1524)
				(type default)
			)
			(layer "F.SilkS")
		)
		(fp_line
			(start -0.7874 0.4064)
			(end -0.7874 -0.4064)
			(stroke
				(width 0.1524)
				(type default)
			)
			(layer "F.SilkS")
		)
		(fp_line
			(start -0.12065 -0.305054)
			(end -0.12065 -0.2794)
			(stroke
				(width 0.1)
				(type default)
			)
			(layer "F.Fab")
		)
		(fp_line
			(start -0.67945 -0.305054)
			(end -0.12065 -0.305054)
			(stroke
				(width 0.1)
				(type default)
			)
			(layer "F.Fab")
		)
		(fp_line
			(start 0.67945 -0.3048)
			(end 0.67945 0.3048)
			(stroke
				(width 0.1)
				(type default)
			)
			(layer "F.Fab")
		)
		(fp_line
			(start 0.12065 -0.3048)
			(end 0.67945 -0.3048)
			(stroke
				(width 0.1)
				(type default)
			)
			(layer "F.Fab")
		)
		(fp_line
			(start 0.12065 -0.2794)
			(end 0.12065 -0.3048)
			(stroke
				(width 0.1)
				(type default)
			)
			(layer "F.Fab")
		)
		(fp_line
			(start -0.12065 -0.2794)
			(end 0.12065 -0.2794)
			(stroke
				(width 0.1)
				(type default)
			)
			(layer "F.Fab")
		)
		(fp_line
			(start 0.120396 0.2794)
			(end -0.12065 0.2794)
			(stroke
				(width 0.1)
				(type default)
			)
			(layer "F.Fab")
		)
		(fp_line
			(start -0.12065 0.2794)
			(end -0.12065 0.3048)
			(stroke
				(width 0.1)
				(type default)
			)
			(layer "F.Fab")
		)
		(fp_line
			(start 0.67945 0.3048)
			(end 0.120396 0.3048)
			(stroke
				(width 0.1)
				(type default)
			)
			(layer "F.Fab")
		)
		(fp_line
			(start 0.120396 0.3048)
			(end 0.120396 0.2794)
			(stroke
				(width 0.1)
				(type default)
			)
			(layer "F.Fab")
		)
		(fp_line
			(start -0.12065 0.3048)
			(end -0.67945 0.3048)
			(stroke
				(width 0.1)
				(type default)
			)
			(layer "F.Fab")
		)
		(fp_line
			(start -0.67945 0.3048)
			(end -0.67945 -0.305054)
			(stroke
				(width 0.1)
				(type default)
			)
			(layer "F.Fab")
		)
		(pad "1" smd circle
			(at -0.40005 0 90)
			(size 0 0)
			(layers "F.Cu" "F.Mask" "F.Paste")
			(net "P3V3_AUX")
		)
		(pad "2" smd circle
			(at 0.40005 0 90)
			(size 0 0)
			(layers "F.Cu" "F.Mask" "F.Paste")
			(net "INA230_5_A0")
		)
	)
	(footprint ""
		(layer "F.Cu")
		(at 246.784622 -90.651584 180)
		(property "Reference" "C2037"
			(at 0 0 180)
			(layer "F.SilkS")
			(hide yes)
			(effects
				(font
					(size 1.27 1.27)
				)
			)
		)
		(property "Value" ""
			(at 0 0 180)
			(layer "F.Fab")
			(effects
				(font
					(size 1.27 1.27)
				)
			)
		)
		(duplicate_pad_numbers_are_jumpers no)
		(fp_line
			(start 0.7874 0.4064)
			(end -0.7874 0.4064)
			(stroke
				(width 0.1524)
				(type default)
			)
			(layer "F.SilkS")
		)
		(fp_line
			(start 0.7874 -0.4064)
			(end 0.7874 0.4064)
			(stroke
				(width 0.1524)
				(type default)
			)
			(layer "F.SilkS")
		)
		(fp_line
			(start -0.7874 0.4064)
			(end -0.7874 -0.4064)
			(stroke
				(width 0.1524)
				(type default)
			)
			(layer "F.SilkS")
		)
		(fp_line
			(start -0.7874 -0.4064)
			(end 0.7874 -0.4064)
			(stroke
				(width 0.1524)
				(type default)
			)
			(layer "F.SilkS")
		)
		(fp_line
			(start 0.67945 0.3048)
			(end 0.120396 0.3048)
			(stroke
				(width 0.1)
				(type default)
			)
			(layer "F.Fab")
		)
		(fp_line
			(start 0.67945 -0.3048)
			(end 0.67945 0.3048)
			(stroke
				(width 0.1)
				(type default)
			)
			(layer "F.Fab")
		)
		(fp_line
			(start 0.12065 -0.2794)
			(end 0.12065 -0.3048)
			(stroke
				(width 0.1)
				(type default)
			)
			(layer "F.Fab")
		)
		(fp_line
			(start 0.12065 -0.3048)
			(end 0.67945 -0.3048)
			(stroke
				(width 0.1)
				(type default)
			)
			(layer "F.Fab")
		)
		(fp_line
			(start 0.120396 0.3048)
			(end 0.120396 0.2794)
			(stroke
				(width 0.1)
				(type default)
			)
			(layer "F.Fab")
		)
		(fp_line
			(start 0.120396 0.2794)
			(end -0.12065 0.2794)
			(stroke
				(width 0.1)
				(type default)
			)
			(layer "F.Fab")
		)
		(fp_line
			(start -0.12065 0.3048)
			(end -0.67945 0.3048)
			(stroke
				(width 0.1)
				(type default)
			)
			(layer "F.Fab")
		)
		(fp_line
			(start -0.12065 0.2794)
			(end -0.12065 0.3048)
			(stroke
				(width 0.1)
				(type default)
			)
			(layer "F.Fab")
		)
		(fp_line
			(start -0.12065 -0.2794)
			(end 0.12065 -0.2794)
			(stroke
				(width 0.1)
				(type default)
			)
			(layer "F.Fab")
		)
		(fp_line
			(start -0.12065 -0.305054)
			(end -0.12065 -0.2794)
			(stroke
				(width 0.1)
				(type default)
			)
			(layer "F.Fab")
		)
		(fp_line
			(start -0.67945 0.3048)
			(end -0.67945 -0.305054)
			(stroke
				(width 0.1)
				(type default)
			)
			(layer "F.Fab")
		)
		(fp_line
			(start -0.67945 -0.305054)
			(end -0.12065 -0.305054)
			(stroke
				(width 0.1)
				(type default)
			)
			(layer "F.Fab")
		)
		(pad "1" smd circle
			(at -0.40005 0 180)
			(size 0 0)
			(layers "F.Cu" "F.Mask" "F.Paste")
			(net "XTAL_CLK_GEN1_25M_X2")
		)
		(pad "2" smd circle
			(at 0.40005 0 180)
			(size 0 0)
			(layers "F.Cu" "F.Mask" "F.Paste")
			(net "GND")
		)
	)
)
